#ISCELL
  mstr_misc dns *
  *
#ISCELL
  mstr_symbols cad_note *
  *
#ISCELL
  mstr_symbols intel_corp_bpage *
  *
#ISCELL
  mstr_symbols vcc_core *
  page101_i100
#ISCELL
  mstr_symbols vcc_core *
  page101_i101
#ISCELL
  mstr_symbols vcc_core *
  page101_i102
#ISCELL
  mstr_symbols vcc_core *
  page101_i103
#CELL
  dev_discrete cap_a *
  page101_i104
#CELL
  mstr_discrete res *
  page101_i105
#CELL
  dev_discrete cap_a *
  page101_i106
#ISCELL
  mstr_symbols gnd *
  page101_i107
#ISCELL
  mstr_symbols gnd *
  page101_i108
#CELL
  dev_discrete cap_a *
  page101_i109
#CELL
  dev_discrete cap_a *
  page101_i110
#CELL
  dev_discrete cap_a *
  page101_i111
#CELL
  dev_discrete cap_a *
  page101_i112
#CELL
  mstr_discrete cap *
  page101_i113
#CELL
  mstr_discrete ferrite *
  page101_i114
#ISCELL
  mstr_symbols p3v3_stby *
  page101_i115
#CELL
  dev_discrete cap_a *
  page101_i116
#ISCELL
  mstr_symbols vcc_core *
  page101_i117
#ISCELL
  mstr_symbols vcc_core *
  page101_i118
#ISCELL
  mstr_symbols vcc_core *
  page101_i119
#ISCELL
  mstr_symbols vcc_core *
  page101_i120
#ISCELL
  mstr_symbols vcc_core *
  page101_i121
#ISCELL
  mstr_symbols vcc_core *
  page101_i122
#ISCELL
  mstr_symbols vcc_core *
  page101_i123
#CELL
  mstr_discrete res *
  page101_i124
#CELL
  mstr_discrete res *
  page101_i125
#ISCELL
  mstr_standard offpage *
  page101_i13
#CELL
  mstr_discrete res *
  page101_i130
#CELL
  mstr_discrete res *
  page101_i134
#CELL
  mstr_discrete res *
  page101_i135
#ISCELL
  mstr_standard offpage *
  page101_i136
#ISCELL
  mstr_standard offpage *
  page101_i137
#CELL
  mstr_discrete res *
  page101_i138
#CELL
  mstr_discrete cap *
  page101_i139
#ISCELL
  mstr_standard offpage *
  page101_i14
#CELL
  mstr_discrete res *
  page101_i140
#ISCELL
  mstr_symbols gnd *
  page101_i141
#CELL
  mstr_discrete res *
  page101_i142
#CELL
  mstr_discrete res *
  page101_i143
#CELL
  mstr_discrete res *
  page101_i144
#CELL
  mstr_discrete res *
  page101_i145
#CELL
  mstr_discrete cap *
  page101_i146
#CELL
  mstr_discrete cap *
  page101_i147
#CELL
  mstr_discrete res *
  page101_i20
#CELL
  mstr_discrete res *
  page101_i28
#ISCELL
  mstr_symbols gnd *
  page101_i29
#ISCELL
  mstr_symbols gnd *
  page101_i33
#CELL
  mstr_clock ics9fgp204 *
  page101_i34
#CELL
  mstr_discrete res *
  page101_i48
#CELL
  mstr_discrete crystal *
  page101_i52
#ISCELL
  mstr_symbols gnd *
  page101_i54
#ISCELL
  mstr_standard offpage *
  page101_i55
#ISCELL
  mstr_symbols gnd *
  page101_i58
#ISCELL
  mstr_symbols gnd *
  page101_i64
#ISCELL
  mstr_standard offpage *
  page101_i71
#ISCELL
  mstr_standard offpage *
  page101_i72
#ISCELL
  mstr_standard offpage *
  page101_i79
#ISCELL
  mstr_standard offpage *
  page101_i80
#ISCELL
  mstr_standard offpage *
  page101_i81
#ISCELL
  mstr_standard offpage *
  page101_i87
#CELL
  dev_discrete cap_a *
  page101_i89
#CELL
  dev_discrete cap_a *
  page101_i90
#CELL
  mstr_discrete res *
  page101_i94
#CELL
  mstr_discrete res *
  page101_i95
#ISCELL
  mstr_symbols gnd *
  page101_i96
#CELL
  dev_discrete cap_a *
  page101_i97
#ISCELL
  mstr_symbols gnd *
  page101_i98
#CELL
  dev_discrete cap_a *
  page101_i99
